# BASEBOARD_FAB2 (Tioga Pass) — schematic netlist excerpt (pin names and nets, part order shuffled) for the footprints in the layout excerpt that follows; sources: Cadence DE-HDL packaged netlist, KiCad conversion of Wiwynn_Tioga_Pass_MB.brd

R6T8  RES  100.0 1% CHIP  pkg 0402  page 112 : A = PVCCIO_CPU0 ; B = XDP_CPU_OBSFN_B0_MBP6_N
R9F65  RES  0.0 5% CHIP  pkg 0402  page 158 : A = SP2_BMC_CM_UART_TX_R1 ; B = SP2_BMC_CM_UART_TX_R
R9W35  RES  4.75K 1% CHIP  pkg 0402  page 158 : A = P3V3_STBY ; B = SP2_BMC_CM_UART_RX_R

(kicad_pcb
	(version 20260206)
	(generator "pcbnew")
	(generator_version "10.0")
	(general
		(thickness 1.6)
		(legacy_teardrops no)
	)
	(paper "A4")
	(title_block
		(title "Wiwynn_Tioga_Pass_MB.brd")
		(comment 1 "Tioga Pass / footprints 3538-3540 of 4770")
	)
	(layers
		(0 "F.Cu" signal "TOP")
		(4 "In1.Cu" signal "L2GND")
		(6 "In2.Cu" signal "L3")
		(8 "In3.Cu" signal "L4GND")
		(10 "In4.Cu" signal "L5")
		(12 "In5.Cu" signal "L6GND")
		(14 "In6.Cu" signal "L7VCC")
		(16 "In7.Cu" signal "L8VCC")
		(18 "In8.Cu" signal "L9GND")
		(20 "In9.Cu" signal "L10")
		(22 "In10.Cu" signal "L11GND")
		(24 "In11.Cu" signal "L12")
		(26 "In12.Cu" signal "L13GND")
		(2 "B.Cu" signal "BOTTOM")
		(9 "F.Adhes" user "F.Adhesive")
		(11 "B.Adhes" user "B.Adhesive")
		(13 "F.Paste" user "Package Geometry/Pastemask Top")
		(15 "B.Paste" user "Package Geometry/Pastemask Bottom")
		(5 "F.SilkS" user "Ref Des/Silkscreen Top")
		(7 "B.SilkS" user "Ref Des/Silkscreen Bottom")
		(1 "F.Mask" user "Board Geometry/Soldermask Top")
		(3 "B.Mask" user "Board Geometry/Soldermask Bottom")
		(17 "Dwgs.User" user "User.Drawings")
		(19 "Cmts.User" user "User.Comments")
		(21 "Eco1.User" user "User.Eco1")
		(23 "Eco2.User" user "User.Eco2")
		(25 "Edge.Cuts" user "Board Geometry/Outline")
		(27 "Margin" user)
		(31 "F.CrtYd" user "Package Geometry/Place Bound Top")
		(29 "B.CrtYd" user "Package Geometry/Place Bound Bottom")
		(35 "F.Fab" user "Ref Des/Assembly Top")
		(33 "B.Fab" user "Ref Des/Assembly Bottom")
	)
	(footprint ""
		(layer "B.Cu")
		(at 486.3338 -34.9504 90)
		(property "Reference" "R9W35"
			(at 0.8382 -0.67818 90)
			(unlocked yes)
			(layer "B.SilkS")
			(effects
				(font
					(size 0.4064 0.254)
					(thickness 0.1524)
				)
				(justify left mirror)
			)
		)
		(property "Value" ""
			(at 0 0 90)
			(layer "B.Fab")
			(effects
				(font
					(size 1.27 1.27)
				)
				(justify mirror)
			)
		)
		(duplicate_pad_numbers_are_jumpers no)
		(fp_poly
			(pts
				(xy 0.2794 -0.1016) (xy -0.2794 -0.1016) (xy -0.2794 0.9906) (xy 0.2794 0.9906)
			)
			(stroke
				(width 0)
				(type default)
			)
			(fill no)
			(layer "B.CrtYd")
		)
		(fp_line
			(start 0.2794 -0.1016)
			(end 0.2794 0.9906)
			(stroke
				(width 0.1)
				(type default)
			)
			(layer "B.Fab")
		)
		(fp_line
			(start -0.2794 -0.1016)
			(end 0.2794 -0.1016)
			(stroke
				(width 0.1)
				(type default)
			)
			(layer "B.Fab")
		)
		(fp_line
			(start 0.2794 0.9906)
			(end -0.2794 0.9906)
			(stroke
				(width 0.1)
				(type default)
			)
			(layer "B.Fab")
		)
		(fp_line
			(start -0.2794 0.9906)
			(end -0.2794 -0.1016)
			(stroke
				(width 0.1)
				(type default)
			)
			(layer "B.Fab")
		)
		(pad "1" smd rect
			(at 0 0 270)
			(size 0.508 0.508)
			(layers "B.Cu" "B.Mask" "B.Paste")
			(net "P3V3_STBY")
		)
		(pad "2" smd rect
			(at 0 0.889 270)
			(size 0.508 0.508)
			(layers "B.Cu" "B.Mask" "B.Paste")
			(net "SP2_BMC_CM_UART_RX_R")
		)
		(zone
			(layer "B.Cu")
			(hatch none 0.5)
			(connect_pads
				(clearance 0)
			)
			(min_thickness 0.25)
			(keepout
				(tracks allowed)
				(vias not_allowed)
				(pads allowed)
				(copperpour not_allowed)
				(footprints allowed)
			)
			(placement
				(enabled no)
				(sheetname "")
			)
			(fill
				(thermal_gap 0.5)
				(thermal_bridge_width 0.5)
				(island_removal_mode 0)
			)
			(polygon
				(pts
					(xy 486.5878 -35.2044) (xy 486.5878 -34.6964) (xy 486.9688 -34.6964) (xy 486.9688 -35.2044)
				)
			)
		)
		(zone
			(layer "B.Cu")
			(hatch none 0.5)
			(connect_pads
				(clearance 0)
			)
			(min_thickness 0.25)
			(keepout
				(tracks not_allowed)
				(vias allowed)
				(pads allowed)
				(copperpour not_allowed)
				(footprints allowed)
			)
			(placement
				(enabled no)
				(sheetname "")
			)
			(fill
				(thermal_gap 0.5)
				(thermal_bridge_width 0.5)
				(island_removal_mode 0)
			)
			(polygon
				(pts
					(xy 486.9688 -35.2044) (xy 486.9688 -34.6964) (xy 486.5878 -34.6964) (xy 486.5878 -35.2044)
				)
			)
		)
	)
	(footprint ""
		(layer "B.Cu")
		(at 499.521226 -34.715704 -90)
		(property "Reference" "R9F65"
			(at 0 0 90)
			(layer "B.SilkS")
			(hide yes)
			(effects
				(font
					(size 1.27 1.27)
				)
				(justify mirror)
			)
		)
		(property "Value" ""
			(at 0 0 90)
			(layer "B.Fab")
			(effects
				(font
					(size 1.27 1.27)
				)
				(justify mirror)
			)
		)
		(duplicate_pad_numbers_are_jumpers no)
		(fp_poly
			(pts
				(xy 0.2794 -0.1016) (xy -0.2794 -0.1016) (xy -0.2794 0.9906) (xy 0.2794 0.9906)
			)
			(stroke
				(width 0)
				(type default)
			)
			(fill no)
			(layer "B.CrtYd")
		)
		(fp_line
			(start -0.2794 0.9906)
			(end -0.2794 -0.1016)
			(stroke
				(width 0.1)
				(type default)
			)
			(layer "B.Fab")
		)
		(fp_line
			(start 0.2794 0.9906)
			(end -0.2794 0.9906)
			(stroke
				(width 0.1)
				(type default)
			)
			(layer "B.Fab")
		)
		(fp_line
			(start -0.2794 -0.1016)
			(end 0.2794 -0.1016)
			(stroke
				(width 0.1)
				(type default)
			)
			(layer "B.Fab")
		)
		(fp_line
			(start 0.2794 -0.1016)
			(end 0.2794 0.9906)
			(stroke
				(width 0.1)
				(type default)
			)
			(layer "B.Fab")
		)
		(pad "1" smd rect
			(at 0 0 90)
			(size 0.508 0.508)
			(layers "B.Cu" "B.Mask" "B.Paste")
			(net "SP2_BMC_CM_UART_TX_R1")
		)
		(pad "2" smd rect
			(at 0 0.889 90)
			(size 0.508 0.508)
			(layers "B.Cu" "B.Mask" "B.Paste")
			(net "SP2_BMC_CM_UART_TX_R")
		)
		(zone
			(layer "B.Cu")
			(hatch none 0.5)
			(connect_pads
				(clearance 0)
			)
			(min_thickness 0.25)
			(keepout
				(tracks not_allowed)
				(vias allowed)
				(pads allowed)
				(copperpour not_allowed)
				(footprints allowed)
			)
			(placement
				(enabled no)
				(sheetname "")
			)
			(fill
				(thermal_gap 0.5)
				(thermal_bridge_width 0.5)
				(island_removal_mode 0)
			)
			(polygon
				(pts
					(xy 498.886226 -34.461704) (xy 498.886226 -34.969704) (xy 499.267226 -34.969704) (xy 499.267226 -34.461704)
				)
			)
		)
		(zone
			(layer "B.Cu")
			(hatch none 0.5)
			(connect_pads
				(clearance 0)
			)
			(min_thickness 0.25)
			(keepout
				(tracks allowed)
				(vias not_allowed)
				(pads allowed)
				(copperpour not_allowed)
				(footprints allowed)
			)
			(placement
				(enabled no)
				(sheetname "")
			)
			(fill
				(thermal_gap 0.5)
				(thermal_bridge_width 0.5)
				(island_removal_mode 0)
			)
			(polygon
				(pts
					(xy 499.267226 -34.461704) (xy 499.267226 -34.969704) (xy 498.886226 -34.969704) (xy 498.886226 -34.461704)
				)
			)
		)
	)
	(footprint ""
		(layer "B.Cu")
		(at 180.653182 -20.014692 180)
		(property "Reference" "R6T8"
			(at 0 0 0)
			(layer "B.SilkS")
			(hide yes)
			(effects
				(font
					(size 1.27 1.27)
				)
				(justify mirror)
			)
		)
		(property "Value" ""
			(at 0 0 0)
			(layer "B.Fab")
			(effects
				(font
					(size 1.27 1.27)
				)
				(justify mirror)
			)
		)
		(duplicate_pad_numbers_are_jumpers no)
		(fp_rect
			(start -0.2794 -0.1016)
			(end 0.2794 0.9906)
			(stroke
				(width 0)
				(type default)
			)
			(fill no)
			(layer "B.CrtYd")
		)
		(fp_line
			(start 0.2794 0.9906)
			(end -0.2794 0.9906)
			(stroke
				(width 0.1)
				(type default)
			)
			(layer "B.Fab")
		)
		(fp_line
			(start 0.2794 -0.1016)
			(end 0.2794 0.9906)
			(stroke
				(width 0.1)
				(type default)
			)
			(layer "B.Fab")
		)
		(fp_line
			(start -0.2794 0.9906)
			(end -0.2794 -0.1016)
			(stroke
				(width 0.1)
				(type default)
			)
			(layer "B.Fab")
		)
		(fp_line
			(start -0.2794 -0.1016)
			(end 0.2794 -0.1016)
			(stroke
				(width 0.1)
				(type default)
			)
			(layer "B.Fab")
		)
		(pad "1" smd rect
			(at 0 0)
			(size 0.508 0.508)
			(layers "B.Cu" "B.Mask" "B.Paste")
			(net "PVCCIO_CPU0")
		)
		(pad "2" smd rect
			(at 0 0.889)
			(size 0.508 0.508)
			(layers "B.Cu" "B.Mask" "B.Paste")
			(net "XDP_CPU_OBSFN_B0_MBP6_N")
		)
		(zone
			(layer "B.Cu")
			(hatch none 0.5)
			(connect_pads
				(clearance 0)
			)
			(min_thickness 0.25)
			(keepout
				(tracks allowed)
				(vias not_allowed)
				(pads allowed)
				(copperpour not_allowed)
				(footprints allowed)
			)
			(placement
				(enabled no)
				(sheetname "")
			)
			(fill
				(thermal_gap 0.5)
				(thermal_bridge_width 0.5)
				(island_removal_mode 0)
			)
			(polygon
				(pts
					(xy 180.907182 -20.268692) (xy 180.907182 -20.649692) (xy 180.399182 -20.649692) (xy 180.399182 -20.268692)
				)
			)
		)
		(zone
			(layer "B.Cu")
			(hatch none 0.5)
			(connect_pads
				(clearance 0)
			)
			(min_thickness 0.25)
			(keepout
				(tracks not_allowed)
				(vias allowed)
				(pads allowed)
				(copperpour not_allowed)
				(footprints allowed)
			)
			(placement
				(enabled no)
				(sheetname "")
			)
			(fill
				(thermal_gap 0.5)
				(thermal_bridge_width 0.5)
				(island_removal_mode 0)
			)
			(polygon
				(pts
					(xy 180.907182 -20.268692) (xy 180.907182 -20.649692) (xy 180.399182 -20.649692) (xy 180.399182 -20.268692)
				)
			)
		)
	)
)
